(kicad_pcb
	(version 20260206)
	(generator "pcbnew")
	(generator_version "10.0")
	(general
		(thickness 1.6)
		(legacy_teardrops no)
	)
	(paper "A4")
	(title_block
		(title "01162023_DA0F0TEBIF0_F0T_Expander_BD_F_brd_V02_OCP.brd")
		(comment 1 "Grand Teton / footprints 2722-2728 of 9728")
	)
	(layers
		(0 "F.Cu" signal "TOP")
		(4 "In1.Cu" signal "GND")
		(6 "In2.Cu" signal "VCC")
		(8 "In3.Cu" signal "VCC1")
		(10 "In4.Cu" signal "GND1")
		(12 "In5.Cu" signal "IN1")
		(14 "In6.Cu" signal "GND2")
		(16 "In7.Cu" signal "IN2")
		(18 "In8.Cu" signal "GND3")
		(20 "In9.Cu" signal "IN3")
		(22 "In10.Cu" signal "GND4")
		(24 "In11.Cu" signal "IN4")
		(26 "In12.Cu" signal "GND5")
		(28 "In13.Cu" signal "IN5")
		(30 "In14.Cu" signal "GND6")
		(32 "In15.Cu" signal "IN6")
		(34 "In16.Cu" signal "GND7")
		(2 "B.Cu" signal "BOTTOM")
		(9 "F.Adhes" user "F.Adhesive")
		(11 "B.Adhes" user "B.Adhesive")
		(13 "F.Paste" user "Package Geometry/Pastemask Top")
		(15 "B.Paste" user "Package Geometry/Pastemask Bottom")
		(5 "F.SilkS" user "Ref Des/Silkscreen Top")
		(7 "B.SilkS" user "Ref Des/Silkscreen Bottom")
		(1 "F.Mask" user "Board Geometry/Soldermask Top")
		(3 "B.Mask" user "Board Geometry/Soldermask Bottom")
		(17 "Dwgs.User" user "User.Drawings")
		(19 "Cmts.User" user "User.Comments")
		(21 "Eco1.User" user "User.Eco1")
		(23 "Eco2.User" user "User.Eco2")
		(25 "Edge.Cuts" user "Board Geometry/Outline")
		(27 "Margin" user)
		(31 "F.CrtYd" user "Package Geometry/Place Bound Top")
		(29 "B.CrtYd" user "Package Geometry/Place Bound Bottom")
		(35 "F.Fab" user "Ref Des/Assembly Top")
		(33 "B.Fab" user "Ref Des/Assembly Bottom")
	)
	(footprint ""
		(layer "F.Cu")
		(at 366.381792 -293.816786 -90)
		(property "Reference" "PC196"
			(at 0 0 270)
			(layer "F.SilkS")
			(hide yes)
			(effects
				(font
					(size 1.27 1.27)
				)
			)
		)
		(property "Value" ""
			(at 0 0 270)
			(layer "F.Fab")
			(effects
				(font
					(size 1.27 1.27)
				)
			)
		)
		(duplicate_pad_numbers_are_jumpers no)
		(fp_line
			(start -0.7874 0.4064)
			(end -0.7874 -0.4064)
			(stroke
				(width 0.1524)
				(type default)
			)
			(layer "F.SilkS")
		)
		(fp_line
			(start 0.7874 0.4064)
			(end -0.7874 0.4064)
			(stroke
				(width 0.1524)
				(type default)
			)
			(layer "F.SilkS")
		)
		(fp_line
			(start -0.7874 -0.4064)
			(end 0.7874 -0.4064)
			(stroke
				(width 0.1524)
				(type default)
			)
			(layer "F.SilkS")
		)
		(fp_line
			(start 0.7874 -0.4064)
			(end 0.7874 0.4064)
			(stroke
				(width 0.1524)
				(type default)
			)
			(layer "F.SilkS")
		)
		(fp_line
			(start -0.67945 0.3048)
			(end -0.67945 -0.305054)
			(stroke
				(width 0.1)
				(type default)
			)
			(layer "F.Fab")
		)
		(fp_line
			(start -0.12065 0.3048)
			(end -0.67945 0.3048)
			(stroke
				(width 0.1)
				(type default)
			)
			(layer "F.Fab")
		)
		(fp_line
			(start 0.120396 0.3048)
			(end 0.120396 0.2794)
			(stroke
				(width 0.1)
				(type default)
			)
			(layer "F.Fab")
		)
		(fp_line
			(start 0.67945 0.3048)
			(end 0.120396 0.3048)
			(stroke
				(width 0.1)
				(type default)
			)
			(layer "F.Fab")
		)
		(fp_line
			(start -0.12065 0.2794)
			(end -0.12065 0.3048)
			(stroke
				(width 0.1)
				(type default)
			)
			(layer "F.Fab")
		)
		(fp_line
			(start 0.120396 0.2794)
			(end -0.12065 0.2794)
			(stroke
				(width 0.1)
				(type default)
			)
			(layer "F.Fab")
		)
		(fp_line
			(start -0.12065 -0.2794)
			(end 0.12065 -0.2794)
			(stroke
				(width 0.1)
				(type default)
			)
			(layer "F.Fab")
		)
		(fp_line
			(start 0.12065 -0.2794)
			(end 0.12065 -0.3048)
			(stroke
				(width 0.1)
				(type default)
			)
			(layer "F.Fab")
		)
		(fp_line
			(start 0.12065 -0.3048)
			(end 0.67945 -0.3048)
			(stroke
				(width 0.1)
				(type default)
			)
			(layer "F.Fab")
		)
		(fp_line
			(start 0.67945 -0.3048)
			(end 0.67945 0.3048)
			(stroke
				(width 0.1)
				(type default)
			)
			(layer "F.Fab")
		)
		(fp_line
			(start -0.67945 -0.305054)
			(end -0.12065 -0.305054)
			(stroke
				(width 0.1)
				(type default)
			)
			(layer "F.Fab")
		)
		(fp_line
			(start -0.12065 -0.305054)
			(end -0.12065 -0.2794)
			(stroke
				(width 0.1)
				(type default)
			)
			(layer "F.Fab")
		)
		(pad "1" smd circle
			(at -0.40005 0 270)
			(size 0 0)
			(layers "F.Cu" "F.Mask" "F.Paste")
			(net "P0V8_PEX3")
		)
		(pad "2" smd circle
			(at 0.40005 0 270)
			(size 0 0)
			(layers "F.Cu" "F.Mask" "F.Paste")
			(net "GND")
		)
	)
	(footprint ""
		(layer "F.Cu")
		(at 446.734438 -34.546286 180)
		(property "Reference" "C722"
			(at 0 0 180)
			(layer "F.SilkS")
			(hide yes)
			(effects
				(font
					(size 1.27 1.27)
				)
			)
		)
		(property "Value" ""
			(at 0 0 180)
			(layer "F.Fab")
			(effects
				(font
					(size 1.27 1.27)
				)
			)
		)
		(duplicate_pad_numbers_are_jumpers no)
		(fp_line
			(start 0.299974 0.150114)
			(end -0.299974 0.150114)
			(stroke
				(width 0.1)
				(type default)
			)
			(layer "F.Fab")
		)
		(fp_line
			(start 0.299974 -0.150114)
			(end 0.299974 0.150114)
			(stroke
				(width 0.1)
				(type default)
			)
			(layer "F.Fab")
		)
		(fp_line
			(start -0.299974 0.150114)
			(end -0.299974 -0.150114)
			(stroke
				(width 0.1)
				(type default)
			)
			(layer "F.Fab")
		)
		(fp_line
			(start -0.299974 -0.150114)
			(end 0.299974 -0.150114)
			(stroke
				(width 0.1)
				(type default)
			)
			(layer "F.Fab")
		)
		(pad "1" smd rect
			(at -0.2667 0 180)
			(size 0.3048 0.381)
			(layers "F.Cu" "F.Mask" "F.Paste")
			(net "P5E_PEX3_STN2_TX_DP<35>")
		)
		(pad "2" smd rect
			(at 0.2667 0 180)
			(size 0.3048 0.381)
			(layers "F.Cu" "F.Mask" "F.Paste")
			(net "P5E_PEX3_STN2_TX_C_DP<35>")
		)
	)
	(footprint ""
		(layer "F.Cu")
		(at 6.662674 -393.740386 -90)
		(property "Reference" "R6741"
			(at 0 0 270)
			(layer "F.SilkS")
			(hide yes)
			(effects
				(font
					(size 1.27 1.27)
				)
			)
		)
		(property "Value" ""
			(at 0 0 270)
			(layer "F.Fab")
			(effects
				(font
					(size 1.27 1.27)
				)
			)
		)
		(duplicate_pad_numbers_are_jumpers no)
		(fp_line
			(start -0.7874 0.4064)
			(end -0.7874 -0.4064)
			(stroke
				(width 0.1524)
				(type default)
			)
			(layer "F.SilkS")
		)
		(fp_line
			(start 0.7874 0.4064)
			(end -0.7874 0.4064)
			(stroke
				(width 0.1524)
				(type default)
			)
			(layer "F.SilkS")
		)
		(fp_line
			(start -0.7874 -0.4064)
			(end 0.7874 -0.4064)
			(stroke
				(width 0.1524)
				(type default)
			)
			(layer "F.SilkS")
		)
		(fp_line
			(start 0.7874 -0.4064)
			(end 0.7874 0.4064)
			(stroke
				(width 0.1524)
				(type default)
			)
			(layer "F.SilkS")
		)
		(fp_line
			(start -0.67945 0.3048)
			(end -0.67945 -0.305054)
			(stroke
				(width 0.1)
				(type default)
			)
			(layer "F.Fab")
		)
		(fp_line
			(start -0.12065 0.3048)
			(end -0.67945 0.3048)
			(stroke
				(width 0.1)
				(type default)
			)
			(layer "F.Fab")
		)
		(fp_line
			(start 0.120396 0.3048)
			(end 0.120396 0.2794)
			(stroke
				(width 0.1)
				(type default)
			)
			(layer "F.Fab")
		)
		(fp_line
			(start 0.67945 0.3048)
			(end 0.120396 0.3048)
			(stroke
				(width 0.1)
				(type default)
			)
			(layer "F.Fab")
		)
		(fp_line
			(start -0.12065 0.2794)
			(end -0.12065 0.3048)
			(stroke
				(width 0.1)
				(type default)
			)
			(layer "F.Fab")
		)
		(fp_line
			(start 0.120396 0.2794)
			(end -0.12065 0.2794)
			(stroke
				(width 0.1)
				(type default)
			)
			(layer "F.Fab")
		)
		(fp_line
			(start -0.12065 -0.2794)
			(end 0.12065 -0.2794)
			(stroke
				(width 0.1)
				(type default)
			)
			(layer "F.Fab")
		)
		(fp_line
			(start 0.12065 -0.2794)
			(end 0.12065 -0.3048)
			(stroke
				(width 0.1)
				(type default)
			)
			(layer "F.Fab")
		)
		(fp_line
			(start 0.12065 -0.3048)
			(end 0.67945 -0.3048)
			(stroke
				(width 0.1)
				(type default)
			)
			(layer "F.Fab")
		)
		(fp_line
			(start 0.67945 -0.3048)
			(end 0.67945 0.3048)
			(stroke
				(width 0.1)
				(type default)
			)
			(layer "F.Fab")
		)
		(fp_line
			(start -0.67945 -0.305054)
			(end -0.12065 -0.305054)
			(stroke
				(width 0.1)
				(type default)
			)
			(layer "F.Fab")
		)
		(fp_line
			(start -0.12065 -0.305054)
			(end -0.12065 -0.2794)
			(stroke
				(width 0.1)
				(type default)
			)
			(layer "F.Fab")
		)
		(pad "1" smd circle
			(at -0.40005 0 270)
			(size 0 0)
			(layers "F.Cu" "F.Mask" "F.Paste")
			(net "P3V3_USB_8042")
		)
		(pad "2" smd circle
			(at 0.40005 0 270)
			(size 0 0)
			(layers "F.Cu" "F.Mask" "F.Paste")
			(net "BIC_USB_8042_HUB_OVCUR2")
		)
	)
	(footprint ""
		(layer "F.Cu")
		(at 144.10563 -258.511548 -90)
		(property "Reference" "C3248"
			(at 0 0 270)
			(layer "F.SilkS")
			(hide yes)
			(effects
				(font
					(size 1.27 1.27)
				)
			)
		)
		(property "Value" ""
			(at 0 0 270)
			(layer "F.Fab")
			(effects
				(font
					(size 1.27 1.27)
				)
			)
		)
		(duplicate_pad_numbers_are_jumpers no)
		(fp_line
			(start -1.2954 0.5842)
			(end -1.2954 -0.5842)
			(stroke
				(width 0.1524)
				(type default)
			)
			(layer "F.SilkS")
		)
		(fp_line
			(start 1.2954 0.5842)
			(end -1.2954 0.5842)
			(stroke
				(width 0.1524)
				(type default)
			)
			(layer "F.SilkS")
		)
		(fp_line
			(start -1.2954 -0.5842)
			(end 1.2954 -0.5842)
			(stroke
				(width 0.1524)
				(type default)
			)
			(layer "F.SilkS")
		)
		(fp_line
			(start 1.2954 -0.5842)
			(end 1.2954 0.5842)
			(stroke
				(width 0.1524)
				(type default)
			)
			(layer "F.SilkS")
		)
		(fp_line
			(start -0.8636 0.4572)
			(end -0.8636 0.4064)
			(stroke
				(width 0.1)
				(type default)
			)
			(layer "F.Fab")
		)
		(fp_line
			(start 0.8636 0.4572)
			(end -0.8636 0.4572)
			(stroke
				(width 0.1)
				(type default)
			)
			(layer "F.Fab")
		)
		(fp_line
			(start -1.1938 0.4064)
			(end -1.1938 -0.4064)
			(stroke
				(width 0.1)
				(type default)
			)
			(layer "F.Fab")
		)
		(fp_line
			(start -0.8636 0.4064)
			(end -1.1938 0.4064)
			(stroke
				(width 0.1)
				(type default)
			)
			(layer "F.Fab")
		)
		(fp_line
			(start 0.8636 0.4064)
			(end 0.8636 0.4572)
			(stroke
				(width 0.1)
				(type default)
			)
			(layer "F.Fab")
		)
		(fp_line
			(start 1.1938 0.4064)
			(end 0.8636 0.4064)
			(stroke
				(width 0.1)
				(type default)
			)
			(layer "F.Fab")
		)
		(fp_line
			(start -1.1938 -0.4064)
			(end -0.8636 -0.4064)
			(stroke
				(width 0.1)
				(type default)
			)
			(layer "F.Fab")
		)
		(fp_line
			(start -0.8636 -0.4064)
			(end -0.8636 -0.4572)
			(stroke
				(width 0.1)
				(type default)
			)
			(layer "F.Fab")
		)
		(fp_line
			(start 0.8636 -0.4064)
			(end 1.1938 -0.4064)
			(stroke
				(width 0.1)
				(type default)
			)
			(layer "F.Fab")
		)
		(fp_line
			(start 1.1938 -0.4064)
			(end 1.1938 0.4064)
			(stroke
				(width 0.1)
				(type default)
			)
			(layer "F.Fab")
		)
		(fp_line
			(start -0.8636 -0.4572)
			(end 0.8636 -0.4572)
			(stroke
				(width 0.1)
				(type default)
			)
			(layer "F.Fab")
		)
		(fp_line
			(start 0.8636 -0.4572)
			(end 0.8636 -0.4064)
			(stroke
				(width 0.1)
				(type default)
			)
			(layer "F.Fab")
		)
		(pad "1" smd rect
			(at -0.7366 0 180)
			(size 0.7112 0.8128)
			(layers "F.Cu" "F.Mask" "F.Paste")
			(net "P1V8_VDDA_PEX1_R")
		)
		(pad "2" smd rect
			(at 0.7366 0 180)
			(size 0.7112 0.8128)
			(layers "F.Cu" "F.Mask" "F.Paste")
			(net "GND")
		)
	)
	(footprint ""
		(layer "F.Cu")
		(at 142.947898 -191.767968)
		(property "Reference" "R6665"
			(at 0 0 0)
			(layer "F.SilkS")
			(hide yes)
			(effects
				(font
					(size 1.27 1.27)
				)
			)
		)
		(property "Value" ""
			(at 0 0 0)
			(layer "F.Fab")
			(effects
				(font
					(size 1.27 1.27)
				)
			)
		)
		(duplicate_pad_numbers_are_jumpers no)
		(fp_line
			(start -0.7874 -0.4064)
			(end 0.7874 -0.4064)
			(stroke
				(width 0.1524)
				(type default)
			)
			(layer "F.SilkS")
		)
		(fp_line
			(start -0.7874 0.4064)
			(end -0.7874 -0.4064)
			(stroke
				(width 0.1524)
				(type default)
			)
			(layer "F.SilkS")
		)
		(fp_line
			(start 0.7874 -0.4064)
			(end 0.7874 0.4064)
			(stroke
				(width 0.1524)
				(type default)
			)
			(layer "F.SilkS")
		)
		(fp_line
			(start 0.7874 0.4064)
			(end -0.7874 0.4064)
			(stroke
				(width 0.1524)
				(type default)
			)
			(layer "F.SilkS")
		)
		(fp_line
			(start -0.67945 -0.305054)
			(end -0.12065 -0.305054)
			(stroke
				(width 0.1)
				(type default)
			)
			(layer "F.Fab")
		)
		(fp_line
			(start -0.67945 0.3048)
			(end -0.67945 -0.305054)
			(stroke
				(width 0.1)
				(type default)
			)
			(layer "F.Fab")
		)
		(fp_line
			(start -0.12065 -0.305054)
			(end -0.12065 -0.2794)
			(stroke
				(width 0.1)
				(type default)
			)
			(layer "F.Fab")
		)
		(fp_line
			(start -0.12065 -0.2794)
			(end 0.12065 -0.2794)
			(stroke
				(width 0.1)
				(type default)
			)
			(layer "F.Fab")
		)
		(fp_line
			(start -0.12065 0.2794)
			(end -0.12065 0.3048)
			(stroke
				(width 0.1)
				(type default)
			)
			(layer "F.Fab")
		)
		(fp_line
			(start -0.12065 0.3048)
			(end -0.67945 0.3048)
			(stroke
				(width 0.1)
				(type default)
			)
			(layer "F.Fab")
		)
		(fp_line
			(start 0.120396 0.2794)
			(end -0.12065 0.2794)
			(stroke
				(width 0.1)
				(type default)
			)
			(layer "F.Fab")
		)
		(fp_line
			(start 0.120396 0.3048)
			(end 0.120396 0.2794)
			(stroke
				(width 0.1)
				(type default)
			)
			(layer "F.Fab")
		)
		(fp_line
			(start 0.12065 -0.3048)
			(end 0.67945 -0.3048)
			(stroke
				(width 0.1)
				(type default)
			)
			(layer "F.Fab")
		)
		(fp_line
			(start 0.12065 -0.2794)
			(end 0.12065 -0.3048)
			(stroke
				(width 0.1)
				(type default)
			)
			(layer "F.Fab")
		)
		(fp_line
			(start 0.67945 -0.3048)
			(end 0.67945 0.3048)
			(stroke
				(width 0.1)
				(type default)
			)
			(layer "F.Fab")
		)
		(fp_line
			(start 0.67945 0.3048)
			(end 0.120396 0.3048)
			(stroke
				(width 0.1)
				(type default)
			)
			(layer "F.Fab")
		)
		(pad "1" smd circle
			(at -0.40005 0)
			(size 0 0)
			(layers "F.Cu" "F.Mask" "F.Paste")
			(net "NIC4_CLK_EN_BUF_N")
		)
		(pad "2" smd circle
			(at 0.40005 0)
			(size 0 0)
			(layers "F.Cu" "F.Mask" "F.Paste")
			(net "NIC4_CLK_EN_BUF_R_N")
		)
	)
	(footprint ""
		(layer "F.Cu")
		(at 249.20575 -85.209888)
		(property "Reference" "R1061"
			(at 0 0 0)
			(layer "F.SilkS")
			(hide yes)
			(effects
				(font
					(size 1.27 1.27)
				)
			)
		)
		(property "Value" ""
			(at 0 0 0)
			(layer "F.Fab")
			(effects
				(font
					(size 1.27 1.27)
				)
			)
		)
		(duplicate_pad_numbers_are_jumpers no)
		(fp_line
			(start -0.7874 -0.4064)
			(end 0.7874 -0.4064)
			(stroke
				(width 0.1524)
				(type default)
			)
			(layer "F.SilkS")
		)
		(fp_line
			(start -0.7874 0.4064)
			(end -0.7874 -0.4064)
			(stroke
				(width 0.1524)
				(type default)
			)
			(layer "F.SilkS")
		)
		(fp_line
			(start 0.7874 -0.4064)
			(end 0.7874 0.4064)
			(stroke
				(width 0.1524)
				(type default)
			)
			(layer "F.SilkS")
		)
		(fp_line
			(start 0.7874 0.4064)
			(end -0.7874 0.4064)
			(stroke
				(width 0.1524)
				(type default)
			)
			(layer "F.SilkS")
		)
		(fp_line
			(start -0.67945 -0.305054)
			(end -0.12065 -0.305054)
			(stroke
				(width 0.1)
				(type default)
			)
			(layer "F.Fab")
		)
		(fp_line
			(start -0.67945 0.3048)
			(end -0.67945 -0.305054)
			(stroke
				(width 0.1)
				(type default)
			)
			(layer "F.Fab")
		)
		(fp_line
			(start -0.12065 -0.305054)
			(end -0.12065 -0.2794)
			(stroke
				(width 0.1)
				(type default)
			)
			(layer "F.Fab")
		)
		(fp_line
			(start -0.12065 -0.2794)
			(end 0.12065 -0.2794)
			(stroke
				(width 0.1)
				(type default)
			)
			(layer "F.Fab")
		)
		(fp_line
			(start -0.12065 0.2794)
			(end -0.12065 0.3048)
			(stroke
				(width 0.1)
				(type default)
			)
			(layer "F.Fab")
		)
		(fp_line
			(start -0.12065 0.3048)
			(end -0.67945 0.3048)
			(stroke
				(width 0.1)
				(type default)
			)
			(layer "F.Fab")
		)
		(fp_line
			(start 0.120396 0.2794)
			(end -0.12065 0.2794)
			(stroke
				(width 0.1)
				(type default)
			)
			(layer "F.Fab")
		)
		(fp_line
			(start 0.120396 0.3048)
			(end 0.120396 0.2794)
			(stroke
				(width 0.1)
				(type default)
			)
			(layer "F.Fab")
		)
		(fp_line
			(start 0.12065 -0.3048)
			(end 0.67945 -0.3048)
			(stroke
				(width 0.1)
				(type default)
			)
			(layer "F.Fab")
		)
		(fp_line
			(start 0.12065 -0.2794)
			(end 0.12065 -0.3048)
			(stroke
				(width 0.1)
				(type default)
			)
			(layer "F.Fab")
		)
		(fp_line
			(start 0.67945 -0.3048)
			(end 0.67945 0.3048)
			(stroke
				(width 0.1)
				(type default)
			)
			(layer "F.Fab")
		)
		(fp_line
			(start 0.67945 0.3048)
			(end 0.120396 0.3048)
			(stroke
				(width 0.1)
				(type default)
			)
			(layer "F.Fab")
		)
		(pad "1" smd circle
			(at -0.40005 0)
			(size 0 0)
			(layers "F.Cu" "F.Mask" "F.Paste")
			(net "GND")
		)
		(pad "2" smd circle
			(at 0.40005 0)
			(size 0 0)
			(layers "F.Cu" "F.Mask" "F.Paste")
			(net "CLK_CK440_SMB_ADDR1")
		)
	)
	(footprint ""
		(layer "F.Cu")
		(at 216.937844 -98.806 -90)
		(property "Reference" "R718"
			(at 0 0 270)
			(layer "F.SilkS")
			(hide yes)
			(effects
				(font
					(size 1.27 1.27)
				)
			)
		)
		(property "Value" ""
			(at 0 0 270)
			(layer "F.Fab")
			(effects
				(font
					(size 1.27 1.27)
				)
			)
		)
		(duplicate_pad_numbers_are_jumpers no)
		(fp_line
			(start -0.7874 0.4064)
			(end -0.7874 -0.4064)
			(stroke
				(width 0.1524)
				(type default)
			)
			(layer "F.SilkS")
		)
		(fp_line
			(start 0.7874 0.4064)
			(end -0.7874 0.4064)
			(stroke
				(width 0.1524)
				(type default)
			)
			(layer "F.SilkS")
		)
		(fp_line
			(start -0.7874 -0.4064)
			(end 0.7874 -0.4064)
			(stroke
				(width 0.1524)
				(type default)
			)
			(layer "F.SilkS")
		)
		(fp_line
			(start 0.7874 -0.4064)
			(end 0.7874 0.4064)
			(stroke
				(width 0.1524)
				(type default)
			)
			(layer "F.SilkS")
		)
		(fp_line
			(start -0.67945 0.3048)
			(end -0.67945 -0.305054)
			(stroke
				(width 0.1)
				(type default)
			)
			(layer "F.Fab")
		)
		(fp_line
			(start -0.12065 0.3048)
			(end -0.67945 0.3048)
			(stroke
				(width 0.1)
				(type default)
			)
			(layer "F.Fab")
		)
		(fp_line
			(start 0.120396 0.3048)
			(end 0.120396 0.2794)
			(stroke
				(width 0.1)
				(type default)
			)
			(layer "F.Fab")
		)
		(fp_line
			(start 0.67945 0.3048)
			(end 0.120396 0.3048)
			(stroke
				(width 0.1)
				(type default)
			)
			(layer "F.Fab")
		)
		(fp_line
			(start -0.12065 0.2794)
			(end -0.12065 0.3048)
			(stroke
				(width 0.1)
				(type default)
			)
			(layer "F.Fab")
		)
		(fp_line
			(start 0.120396 0.2794)
			(end -0.12065 0.2794)
			(stroke
				(width 0.1)
				(type default)
			)
			(layer "F.Fab")
		)
		(fp_line
			(start -0.12065 -0.2794)
			(end 0.12065 -0.2794)
			(stroke
				(width 0.1)
				(type default)
			)
			(layer "F.Fab")
		)
		(fp_line
			(start 0.12065 -0.2794)
			(end 0.12065 -0.3048)
			(stroke
				(width 0.1)
				(type default)
			)
			(layer "F.Fab")
		)
		(fp_line
			(start 0.12065 -0.3048)
			(end 0.67945 -0.3048)
			(stroke
				(width 0.1)
				(type default)
			)
			(layer "F.Fab")
		)
		(fp_line
			(start 0.67945 -0.3048)
			(end 0.67945 0.3048)
			(stroke
				(width 0.1)
				(type default)
			)
			(layer "F.Fab")
		)
		(fp_line
			(start -0.67945 -0.305054)
			(end -0.12065 -0.305054)
			(stroke
				(width 0.1)
				(type default)
			)
			(layer "F.Fab")
		)
		(fp_line
			(start -0.12065 -0.305054)
			(end -0.12065 -0.2794)
			(stroke
				(width 0.1)
				(type default)
			)
			(layer "F.Fab")
		)
		(pad "1" smd circle
			(at -0.40005 0 270)
			(size 0 0)
			(layers "F.Cu" "F.Mask" "F.Paste")
			(net "NIC3_ADC_A1")
		)
		(pad "2" smd circle
			(at 0.40005 0 270)
			(size 0 0)
			(layers "F.Cu" "F.Mask" "F.Paste")
			(net "GND")
		)
	)
)
